# S9S_MB_2U (Grand Teton) — schematic netlist excerpt (pin names and nets, part order shuffled) for the footprints in the layout excerpt that follows; sources: Cadence DE-HDL packaged netlist, KiCad conversion of 03242023_DA0F0TMBIJ0_F0T_Motherboard_J_brd_V01_OCP.brd

C950  Q_CAP_DIFFBUS  DIFF BUS_0.22UF 6.3V 20% X6S  pkg C0201  page 173 : \1\ = P5E_CPU0_PE2_TX_C_DN<7> ; \2\ = P5E_CPU0_PE2_TX_DN<7>
R2512  Q_RES  49.9 1% CHIP  pkg 0402LF  page 239 : A = P1V05_PCH_AUX ; B = P0V7_JTAG_VREF_2
R4661  Q_RES  0 5% EMPTY  pkg 0402LF  page 167 : A = P2E_MB_BMC_TX_C_DP<0> ; B = P2E_MB_BMC_TX_C_R2_DP<0>

(kicad_pcb
	(version 20260206)
	(generator "pcbnew")
	(generator_version "10.0")
	(general
		(thickness 1.6)
		(legacy_teardrops no)
	)
	(paper "A4")
	(title_block
		(title "03242023_DA0F0TMBIJ0_F0T_Motherboard_J_brd_V01_OCP.brd")
		(comment 1 "Grand Teton / footprints 1944-1946 of 6105")
	)
	(layers
		(0 "F.Cu" signal "TOP")
		(4 "In1.Cu" signal "GND")
		(6 "In2.Cu" signal "IN1")
		(8 "In3.Cu" signal "GND1")
		(10 "In4.Cu" signal "IN2")
		(12 "In5.Cu" signal "GND2")
		(14 "In6.Cu" signal "IN3")
		(16 "In7.Cu" signal "GND3")
		(18 "In8.Cu" signal "VCC")
		(20 "In9.Cu" signal "VCC1")
		(22 "In10.Cu" signal "GND4")
		(24 "In11.Cu" signal "IN4")
		(26 "In12.Cu" signal "GND5")
		(28 "In13.Cu" signal "IN5")
		(30 "In14.Cu" signal "GND6")
		(32 "In15.Cu" signal "IN6")
		(34 "In16.Cu" signal "GND7")
		(2 "B.Cu" signal "BOTTOM")
		(9 "F.Adhes" user "F.Adhesive")
		(11 "B.Adhes" user "B.Adhesive")
		(13 "F.Paste" user "Package Geometry/Pastemask Top")
		(15 "B.Paste" user "Package Geometry/Pastemask Bottom")
		(5 "F.SilkS" user "Ref Des/Silkscreen Top")
		(7 "B.SilkS" user "Ref Des/Silkscreen Bottom")
		(1 "F.Mask" user "Board Geometry/Soldermask Top")
		(3 "B.Mask" user "Board Geometry/Soldermask Bottom")
		(17 "Dwgs.User" user "User.Drawings")
		(19 "Cmts.User" user "User.Comments")
		(21 "Eco1.User" user "User.Eco1")
		(23 "Eco2.User" user "User.Eco2")
		(25 "Edge.Cuts" user "Board Geometry/Outline")
		(27 "Margin" user)
		(31 "F.CrtYd" user "Package Geometry/Place Bound Top")
		(29 "B.CrtYd" user "Package Geometry/Place Bound Bottom")
		(35 "F.Fab" user "Ref Des/Assembly Top")
		(33 "B.Fab" user "Ref Des/Assembly Bottom")
	)
	(footprint ""
		(layer "F.Cu")
		(at 19.19859 -385.065524 -90)
		(property "Reference" "R4661"
			(at 0 0 270)
			(layer "F.SilkS")
			(hide yes)
			(effects
				(font
					(size 1.27 1.27)
				)
			)
		)
		(property "Value" ""
			(at 0 0 270)
			(layer "F.Fab")
			(effects
				(font
					(size 1.27 1.27)
				)
			)
		)
		(duplicate_pad_numbers_are_jumpers no)
		(fp_line
			(start -0.7874 0.4064)
			(end -0.7874 -0.4064)
			(stroke
				(width 0.1524)
				(type default)
			)
			(layer "F.SilkS")
		)
		(fp_line
			(start 0.7874 0.4064)
			(end -0.7874 0.4064)
			(stroke
				(width 0.1524)
				(type default)
			)
			(layer "F.SilkS")
		)
		(fp_line
			(start 0.029464 -0.4064)
			(end 0.7874 -0.4064)
			(stroke
				(width 0.1524)
				(type default)
			)
			(layer "F.SilkS")
		)
		(fp_line
			(start -0.67945 0.3048)
			(end -0.67945 -0.305054)
			(stroke
				(width 0.1)
				(type default)
			)
			(layer "F.Fab")
		)
		(fp_line
			(start -0.12065 0.3048)
			(end -0.67945 0.3048)
			(stroke
				(width 0.1)
				(type default)
			)
			(layer "F.Fab")
		)
		(fp_line
			(start 0.120396 0.3048)
			(end 0.120396 0.2794)
			(stroke
				(width 0.1)
				(type default)
			)
			(layer "F.Fab")
		)
		(fp_line
			(start 0.67945 0.3048)
			(end 0.120396 0.3048)
			(stroke
				(width 0.1)
				(type default)
			)
			(layer "F.Fab")
		)
		(fp_line
			(start -0.12065 0.2794)
			(end -0.12065 0.3048)
			(stroke
				(width 0.1)
				(type default)
			)
			(layer "F.Fab")
		)
		(fp_line
			(start 0.120396 0.2794)
			(end -0.12065 0.2794)
			(stroke
				(width 0.1)
				(type default)
			)
			(layer "F.Fab")
		)
		(fp_line
			(start -0.12065 -0.2794)
			(end 0.12065 -0.2794)
			(stroke
				(width 0.1)
				(type default)
			)
			(layer "F.Fab")
		)
		(fp_line
			(start 0.12065 -0.2794)
			(end 0.12065 -0.3048)
			(stroke
				(width 0.1)
				(type default)
			)
			(layer "F.Fab")
		)
		(fp_line
			(start 0.12065 -0.3048)
			(end 0.67945 -0.3048)
			(stroke
				(width 0.1)
				(type default)
			)
			(layer "F.Fab")
		)
		(fp_line
			(start 0.67945 -0.3048)
			(end 0.67945 0.3048)
			(stroke
				(width 0.1)
				(type default)
			)
			(layer "F.Fab")
		)
		(fp_line
			(start -0.67945 -0.305054)
			(end -0.12065 -0.305054)
			(stroke
				(width 0.1)
				(type default)
			)
			(layer "F.Fab")
		)
		(fp_line
			(start -0.12065 -0.305054)
			(end -0.12065 -0.2794)
			(stroke
				(width 0.1)
				(type default)
			)
			(layer "F.Fab")
		)
		(pad "1" smd rect
			(at -0.40005 0 90)
			(size 0.4572 0.508)
			(layers "F.Cu" "F.Mask" "F.Paste")
			(net "P2E_MB_BMC_TX_C_DP<0>")
		)
		(pad "2" smd rect
			(at 0.40005 0 90)
			(size 0.4572 0.508)
			(layers "F.Cu" "F.Mask" "F.Paste")
			(net "P2E_MB_BMC_TX_C_R2_DP<0>")
		)
	)
	(footprint ""
		(layer "F.Cu")
		(at 377.54052 -109.720888)
		(property "Reference" "R2512"
			(at 0 0 0)
			(layer "F.SilkS")
			(hide yes)
			(effects
				(font
					(size 1.27 1.27)
				)
			)
		)
		(property "Value" ""
			(at 0 0 0)
			(layer "F.Fab")
			(effects
				(font
					(size 1.27 1.27)
				)
			)
		)
		(duplicate_pad_numbers_are_jumpers no)
		(fp_line
			(start -0.7874 -0.4064)
			(end 0.7874 -0.4064)
			(stroke
				(width 0.1524)
				(type default)
			)
			(layer "F.SilkS")
		)
		(fp_line
			(start -0.7874 0.4064)
			(end -0.7874 -0.4064)
			(stroke
				(width 0.1524)
				(type default)
			)
			(layer "F.SilkS")
		)
		(fp_line
			(start 0.7874 -0.4064)
			(end 0.7874 0.4064)
			(stroke
				(width 0.1524)
				(type default)
			)
			(layer "F.SilkS")
		)
		(fp_line
			(start 0.7874 0.4064)
			(end -0.7874 0.4064)
			(stroke
				(width 0.1524)
				(type default)
			)
			(layer "F.SilkS")
		)
		(fp_line
			(start -0.67945 -0.305054)
			(end -0.12065 -0.305054)
			(stroke
				(width 0.1)
				(type default)
			)
			(layer "F.Fab")
		)
		(fp_line
			(start -0.67945 0.3048)
			(end -0.67945 -0.305054)
			(stroke
				(width 0.1)
				(type default)
			)
			(layer "F.Fab")
		)
		(fp_line
			(start -0.12065 -0.305054)
			(end -0.12065 -0.2794)
			(stroke
				(width 0.1)
				(type default)
			)
			(layer "F.Fab")
		)
		(fp_line
			(start -0.12065 -0.2794)
			(end 0.12065 -0.2794)
			(stroke
				(width 0.1)
				(type default)
			)
			(layer "F.Fab")
		)
		(fp_line
			(start -0.12065 0.2794)
			(end -0.12065 0.3048)
			(stroke
				(width 0.1)
				(type default)
			)
			(layer "F.Fab")
		)
		(fp_line
			(start -0.12065 0.3048)
			(end -0.67945 0.3048)
			(stroke
				(width 0.1)
				(type default)
			)
			(layer "F.Fab")
		)
		(fp_line
			(start 0.120396 0.2794)
			(end -0.12065 0.2794)
			(stroke
				(width 0.1)
				(type default)
			)
			(layer "F.Fab")
		)
		(fp_line
			(start 0.120396 0.3048)
			(end 0.120396 0.2794)
			(stroke
				(width 0.1)
				(type default)
			)
			(layer "F.Fab")
		)
		(fp_line
			(start 0.12065 -0.3048)
			(end 0.67945 -0.3048)
			(stroke
				(width 0.1)
				(type default)
			)
			(layer "F.Fab")
		)
		(fp_line
			(start 0.12065 -0.2794)
			(end 0.12065 -0.3048)
			(stroke
				(width 0.1)
				(type default)
			)
			(layer "F.Fab")
		)
		(fp_line
			(start 0.67945 -0.3048)
			(end 0.67945 0.3048)
			(stroke
				(width 0.1)
				(type default)
			)
			(layer "F.Fab")
		)
		(fp_line
			(start 0.67945 0.3048)
			(end 0.120396 0.3048)
			(stroke
				(width 0.1)
				(type default)
			)
			(layer "F.Fab")
		)
		(pad "1" smd circle
			(at -0.40005 0)
			(size 0 0)
			(layers "F.Cu" "F.Mask" "F.Paste")
			(net "P1V05_PCH_AUX")
		)
		(pad "2" smd circle
			(at 0.40005 0)
			(size 0 0)
			(layers "F.Cu" "F.Mask" "F.Paste")
			(net "P0V7_JTAG_VREF_2")
		)
	)
	(footprint ""
		(layer "F.Cu")
		(at 396.81785 -402.371052 -90)
		(property "Reference" "C950"
			(at 0 0 270)
			(layer "F.SilkS")
			(hide yes)
			(effects
				(font
					(size 1.27 1.27)
				)
			)
		)
		(property "Value" ""
			(at 0 0 270)
			(layer "F.Fab")
			(effects
				(font
					(size 1.27 1.27)
				)
			)
		)
		(duplicate_pad_numbers_are_jumpers no)
		(fp_line
			(start -0.299974 0.150114)
			(end -0.299974 -0.150114)
			(stroke
				(width 0.1)
				(type default)
			)
			(layer "F.Fab")
		)
		(fp_line
			(start 0.299974 0.150114)
			(end -0.299974 0.150114)
			(stroke
				(width 0.1)
				(type default)
			)
			(layer "F.Fab")
		)
		(fp_line
			(start -0.299974 -0.150114)
			(end 0.299974 -0.150114)
			(stroke
				(width 0.1)
				(type default)
			)
			(layer "F.Fab")
		)
		(fp_line
			(start 0.299974 -0.150114)
			(end 0.299974 0.150114)
			(stroke
				(width 0.1)
				(type default)
			)
			(layer "F.Fab")
		)
		(pad "1" smd rect
			(at -0.2667 0 270)
			(size 0.3048 0.381)
			(layers "F.Cu" "F.Mask" "F.Paste")
			(net "P5E_CPU0_PE2_TX_C_DN<7>")
		)
		(pad "2" smd rect
			(at 0.2667 0 270)
			(size 0.3048 0.381)
			(layers "F.Cu" "F.Mask" "F.Paste")
			(net "P5E_CPU0_PE2_TX_DN<7>")
		)
	)
)
